(kicad_pcb
	(version 20260206)
	(generator "pcbnew")
	(generator_version "10.0")
	(general
		(thickness 1.6)
		(legacy_teardrops no)
	)
	(paper "A4")
	(title_block
		(title "peb — Lightning_PEB_BRD.brd")
		(comment 1 "Lightning (Wiwynn / Facebook NVMe JBOF) / footprints 2272-2278 of 2563")
	)
	(layers
		(0 "F.Cu" signal "TOP")
		(4 "In1.Cu" signal "L2GND")
		(6 "In2.Cu" signal "L3")
		(8 "In3.Cu" signal "L4VCC")
		(10 "In4.Cu" signal "L5VCC")
		(12 "In5.Cu" signal "L6")
		(14 "In6.Cu" signal "L7GND")
		(2 "B.Cu" signal "BOTTOM")
		(9 "F.Adhes" user "F.Adhesive")
		(11 "B.Adhes" user "B.Adhesive")
		(13 "F.Paste" user "Package Geometry/Pastemask Top")
		(15 "B.Paste" user "Package Geometry/Pastemask Bottom")
		(5 "F.SilkS" user "Ref Des/Silkscreen Top")
		(7 "B.SilkS" user "Ref Des/Silkscreen Bottom")
		(1 "F.Mask" user "Board Geometry/Soldermask Top")
		(3 "B.Mask" user "Board Geometry/Soldermask Bottom")
		(17 "Dwgs.User" user "User.Drawings")
		(19 "Cmts.User" user "User.Comments")
		(21 "Eco1.User" user "User.Eco1")
		(23 "Eco2.User" user "User.Eco2")
		(25 "Edge.Cuts" user "Board Geometry/Outline")
		(27 "Margin" user)
		(31 "F.CrtYd" user "Package Geometry/Place Bound Top")
		(29 "B.CrtYd" user "Package Geometry/Place Bound Bottom")
		(35 "F.Fab" user "Ref Des/Assembly Top")
		(33 "B.Fab" user "Ref Des/Assembly Bottom")
	)
	(footprint ""
		(layer "B.Cu")
		(at 50.165 -145.415 180)
		(property "Reference" "SR847"
			(at 0 0 0)
			(layer "B.SilkS")
			(hide yes)
			(effects
				(font
					(size 1.27 1.27)
				)
				(justify mirror)
			)
		)
		(property "Value" "4K75R2F-1-GP"
			(at -0.064008 -3.993896 180)
			(unlocked yes)
			(layer "B.Fab")
			(hide yes)
			(effects
				(font
					(size 1.016 1.016)
					(thickness 0.1524)
				)
				(justify mirror)
			)
		)
		(property "Device Type" "R402H16"
			(at -0.064008 -5.517896 180)
			(unlocked yes)
			(layer "B.Fab")
			(hide yes)
			(effects
				(font
					(size 1.016 1.016)
					(thickness 0.1524)
				)
				(justify mirror)
			)
		)
		(duplicate_pad_numbers_are_jumpers no)
		(fp_line
			(start 0.508 -0.9398)
			(end 0.508 0.9398)
			(stroke
				(width 0.1524)
				(type default)
			)
			(layer "B.SilkS")
		)
		(fp_line
			(start -0.508 -0.9398)
			(end 0.508 -0.9398)
			(stroke
				(width 0.1524)
				(type default)
			)
			(layer "B.SilkS")
		)
		(fp_rect
			(start 0.508 0.9398)
			(end -0.508 -0.9398)
			(stroke
				(width 0)
				(type default)
			)
			(fill no)
			(layer "B.CrtYd")
		)
		(fp_rect
			(start 0.508 0.9398)
			(end -0.508 -0.9398)
			(stroke
				(width 0)
				(type default)
			)
			(fill no)
			(layer "B.Fab")
		)
		(pad "1" smd custom
			(at 0 -0.4445)
			(size 0.1397 0.1397)
			(layers "B.Cu" "B.Mask" "B.Paste")
			(net "BMC_FW_DET_BOARD_VER_2")
			(options
				(clearance outline)
				(anchor circle)
			)
			(primitives
				(gr_poly
					(pts
						(arc
							(start -0.1778 0.2794)
							(mid -0.249642 0.249642)
							(end -0.2794 0.1778)
						)
						(arc
							(start -0.2794 -0.1778)
							(mid -0.249642 -0.249642)
							(end -0.1778 -0.2794)
						)
						(arc
							(start 0.1778 -0.2794)
							(mid 0.249642 -0.249642)
							(end 0.2794 -0.1778)
						)
						(arc
							(start 0.2794 0.1778)
							(mid 0.249642 0.249642)
							(end 0.1778 0.2794)
						)
					)
					(width 0)
					(fill yes)
				)
			)
		)
		(pad "2" smd custom
			(at 0 0.4445)
			(size 0.1397 0.1397)
			(layers "B.Cu" "B.Mask" "B.Paste")
			(net "GND")
			(options
				(clearance outline)
				(anchor circle)
			)
			(primitives
				(gr_poly
					(pts
						(arc
							(start -0.1778 0.2794)
							(mid -0.249642 0.249642)
							(end -0.2794 0.1778)
						)
						(arc
							(start -0.2794 -0.1778)
							(mid -0.249642 -0.249642)
							(end -0.1778 -0.2794)
						)
						(arc
							(start 0.1778 -0.2794)
							(mid 0.249642 -0.249642)
							(end 0.2794 -0.1778)
						)
						(arc
							(start 0.2794 0.1778)
							(mid 0.249642 0.249642)
							(end 0.1778 0.2794)
						)
					)
					(width 0)
					(fill yes)
				)
			)
		)
	)
	(footprint ""
		(layer "B.Cu")
		(at 59.218322 -124.441966 90)
		(property "Reference" "R421"
			(at 0 0 90)
			(layer "B.SilkS")
			(hide yes)
			(effects
				(font
					(size 1.27 1.27)
				)
				(justify mirror)
			)
		)
		(property "Value" "4K7R2F-GP"
			(at -0.064008 -3.993896 90)
			(unlocked yes)
			(layer "B.Fab")
			(hide yes)
			(effects
				(font
					(size 1.016 1.016)
					(thickness 0.1524)
				)
				(justify mirror)
			)
		)
		(property "Device Type" "R402H16"
			(at -0.064008 -5.517896 90)
			(unlocked yes)
			(layer "B.Fab")
			(hide yes)
			(effects
				(font
					(size 1.016 1.016)
					(thickness 0.1524)
				)
				(justify mirror)
			)
		)
		(duplicate_pad_numbers_are_jumpers no)
		(fp_line
			(start 0.508 -0.9398)
			(end 0.508 0.9398)
			(stroke
				(width 0.1524)
				(type default)
			)
			(layer "B.SilkS")
		)
		(fp_line
			(start -0.508 -0.9398)
			(end 0.508 -0.9398)
			(stroke
				(width 0.1524)
				(type default)
			)
			(layer "B.SilkS")
		)
		(fp_rect
			(start 0.508 0.9398)
			(end -0.508 -0.9398)
			(stroke
				(width 0)
				(type default)
			)
			(fill no)
			(layer "B.CrtYd")
		)
		(fp_rect
			(start 0.508 0.9398)
			(end -0.508 -0.9398)
			(stroke
				(width 0)
				(type default)
			)
			(fill no)
			(layer "B.Fab")
		)
		(pad "1" smd custom
			(at 0 -0.4445 270)
			(size 0.1397 0.1397)
			(layers "B.Cu" "B.Mask" "B.Paste")
			(net "BMC_I2C8_CLKBUF1_SCL")
			(options
				(clearance outline)
				(anchor circle)
			)
			(primitives
				(gr_poly
					(pts
						(arc
							(start -0.1778 0.2794)
							(mid -0.249642 0.249642)
							(end -0.2794 0.1778)
						)
						(arc
							(start -0.2794 -0.1778)
							(mid -0.249642 -0.249642)
							(end -0.1778 -0.2794)
						)
						(arc
							(start 0.1778 -0.2794)
							(mid 0.249642 -0.249642)
							(end 0.2794 -0.1778)
						)
						(arc
							(start 0.2794 0.1778)
							(mid 0.249642 0.249642)
							(end 0.1778 0.2794)
						)
					)
					(width 0)
					(fill yes)
				)
			)
		)
		(pad "2" smd custom
			(at 0 0.4445 270)
			(size 0.1397 0.1397)
			(layers "B.Cu" "B.Mask" "B.Paste")
			(net "P3V3_STBY")
			(options
				(clearance outline)
				(anchor circle)
			)
			(primitives
				(gr_poly
					(pts
						(arc
							(start -0.1778 0.2794)
							(mid -0.249642 0.249642)
							(end -0.2794 0.1778)
						)
						(arc
							(start -0.2794 -0.1778)
							(mid -0.249642 -0.249642)
							(end -0.1778 -0.2794)
						)
						(arc
							(start 0.1778 -0.2794)
							(mid 0.249642 -0.249642)
							(end 0.2794 -0.1778)
						)
						(arc
							(start 0.2794 0.1778)
							(mid 0.249642 0.249642)
							(end 0.1778 0.2794)
						)
					)
					(width 0)
					(fill yes)
				)
			)
		)
	)
	(footprint ""
		(layer "B.Cu")
		(at 336.7786 -181.8386)
		(property "Reference" "R3229"
			(at 0 0 0)
			(layer "B.SilkS")
			(hide yes)
			(effects
				(font
					(size 1.27 1.27)
				)
				(justify mirror)
			)
		)
		(property "Value" "0R2J-2-GP"
			(at -0.064008 -3.993896 0)
			(unlocked yes)
			(layer "B.Fab")
			(hide yes)
			(effects
				(font
					(size 1.016 1.016)
					(thickness 0.1524)
				)
				(justify mirror)
			)
		)
		(property "Device Type" "R402H16"
			(at -0.064008 -5.517896 0)
			(unlocked yes)
			(layer "B.Fab")
			(hide yes)
			(effects
				(font
					(size 1.016 1.016)
					(thickness 0.1524)
				)
				(justify mirror)
			)
		)
		(duplicate_pad_numbers_are_jumpers no)
		(fp_line
			(start -0.508 -0.9398)
			(end 0.508 -0.9398)
			(stroke
				(width 0.1524)
				(type default)
			)
			(layer "B.SilkS")
		)
		(fp_line
			(start 0.508 -0.9398)
			(end 0.508 0.9398)
			(stroke
				(width 0.1524)
				(type default)
			)
			(layer "B.SilkS")
		)
		(fp_rect
			(start 0.508 0.9398)
			(end -0.508 -0.9398)
			(stroke
				(width 0)
				(type default)
			)
			(fill no)
			(layer "B.CrtYd")
		)
		(fp_rect
			(start 0.508 0.9398)
			(end -0.508 -0.9398)
			(stroke
				(width 0)
				(type default)
			)
			(fill no)
			(layer "B.Fab")
		)
		(pad "1" smd custom
			(at 0 -0.4445 180)
			(size 0.1397 0.1397)
			(layers "B.Cu" "B.Mask" "B.Paste")
			(net "BMC_SSD_RST#9")
			(options
				(clearance outline)
				(anchor circle)
			)
			(primitives
				(gr_poly
					(pts
						(arc
							(start -0.1778 0.2794)
							(mid -0.249642 0.249642)
							(end -0.2794 0.1778)
						)
						(arc
							(start -0.2794 -0.1778)
							(mid -0.249642 -0.249642)
							(end -0.1778 -0.2794)
						)
						(arc
							(start 0.1778 -0.2794)
							(mid 0.249642 -0.249642)
							(end 0.2794 -0.1778)
						)
						(arc
							(start 0.2794 0.1778)
							(mid 0.249642 0.249642)
							(end 0.1778 0.2794)
						)
					)
					(width 0)
					(fill yes)
				)
			)
		)
		(pad "2" smd custom
			(at 0 0.4445 180)
			(size 0.1397 0.1397)
			(layers "B.Cu" "B.Mask" "B.Paste")
			(net "BMC_SSD_RST#0_A9")
			(options
				(clearance outline)
				(anchor circle)
			)
			(primitives
				(gr_poly
					(pts
						(arc
							(start -0.1778 0.2794)
							(mid -0.249642 0.249642)
							(end -0.2794 0.1778)
						)
						(arc
							(start -0.2794 -0.1778)
							(mid -0.249642 -0.249642)
							(end -0.1778 -0.2794)
						)
						(arc
							(start 0.1778 -0.2794)
							(mid 0.249642 -0.249642)
							(end 0.2794 -0.1778)
						)
						(arc
							(start 0.2794 0.1778)
							(mid 0.249642 0.249642)
							(end 0.1778 0.2794)
						)
					)
					(width 0)
					(fill yes)
				)
			)
		)
	)
	(footprint ""
		(layer "B.Cu")
		(at 270.63065 -10.813542)
		(property "Reference" "R723"
			(at 0 0 0)
			(layer "B.SilkS")
			(hide yes)
			(effects
				(font
					(size 1.27 1.27)
				)
				(justify mirror)
			)
		)
		(property "Value" "0R2J-2-GP"
			(at -0.064008 -3.993896 0)
			(unlocked yes)
			(layer "B.Fab")
			(hide yes)
			(effects
				(font
					(size 1.016 1.016)
					(thickness 0.1524)
				)
				(justify mirror)
			)
		)
		(property "Device Type" "R402H16"
			(at -0.064008 -5.517896 0)
			(unlocked yes)
			(layer "B.Fab")
			(hide yes)
			(effects
				(font
					(size 1.016 1.016)
					(thickness 0.1524)
				)
				(justify mirror)
			)
		)
		(duplicate_pad_numbers_are_jumpers no)
		(fp_line
			(start -0.508 -0.9398)
			(end 0.508 -0.9398)
			(stroke
				(width 0.1524)
				(type default)
			)
			(layer "B.SilkS")
		)
		(fp_line
			(start 0.508 -0.9398)
			(end 0.508 0.9398)
			(stroke
				(width 0.1524)
				(type default)
			)
			(layer "B.SilkS")
		)
		(fp_rect
			(start 0.508 0.9398)
			(end -0.508 -0.9398)
			(stroke
				(width 0)
				(type default)
			)
			(fill no)
			(layer "B.CrtYd")
		)
		(fp_rect
			(start 0.508 0.9398)
			(end -0.508 -0.9398)
			(stroke
				(width 0)
				(type default)
			)
			(fill no)
			(layer "B.Fab")
		)
		(pad "1" smd custom
			(at 0 -0.4445 180)
			(size 0.1397 0.1397)
			(layers "B.Cu" "B.Mask" "B.Paste")
			(net "HOST6_RST_N_C")
			(options
				(clearance outline)
				(anchor circle)
			)
			(primitives
				(gr_poly
					(pts
						(arc
							(start -0.1778 0.2794)
							(mid -0.249642 0.249642)
							(end -0.2794 0.1778)
						)
						(arc
							(start -0.2794 -0.1778)
							(mid -0.249642 -0.249642)
							(end -0.1778 -0.2794)
						)
						(arc
							(start 0.1778 -0.2794)
							(mid 0.249642 -0.249642)
							(end 0.2794 -0.1778)
						)
						(arc
							(start 0.2794 0.1778)
							(mid 0.249642 0.249642)
							(end 0.1778 0.2794)
						)
					)
					(width 0)
					(fill yes)
				)
			)
		)
		(pad "2" smd custom
			(at 0 0.4445 180)
			(size 0.1397 0.1397)
			(layers "B.Cu" "B.Mask" "B.Paste")
			(net "P3V3_STBY")
			(options
				(clearance outline)
				(anchor circle)
			)
			(primitives
				(gr_poly
					(pts
						(arc
							(start -0.1778 0.2794)
							(mid -0.249642 0.249642)
							(end -0.2794 0.1778)
						)
						(arc
							(start -0.2794 -0.1778)
							(mid -0.249642 -0.249642)
							(end -0.1778 -0.2794)
						)
						(arc
							(start 0.1778 -0.2794)
							(mid 0.249642 -0.249642)
							(end 0.2794 -0.1778)
						)
						(arc
							(start 0.2794 0.1778)
							(mid 0.249642 0.249642)
							(end 0.1778 0.2794)
						)
					)
					(width 0)
					(fill yes)
				)
			)
		)
	)
	(footprint ""
		(layer "B.Cu")
		(at 298.489624 -34.625026 180)
		(property "Reference" "C131"
			(at 0 0 0)
			(layer "B.SilkS")
			(hide yes)
			(effects
				(font
					(size 1.27 1.27)
				)
				(justify mirror)
			)
		)
		(property "Value" "SCD1U10V2KX-5GP"
			(at -1.1811 -2.7051 180)
			(unlocked yes)
			(layer "B.Fab")
			(hide yes)
			(effects
				(font
					(size 1.016 1.016)
					(thickness 0.1524)
				)
				(justify mirror)
			)
		)
		(property "Device Type" "C402H22"
			(at -1.1811 -4.2291 180)
			(unlocked yes)
			(layer "B.Fab")
			(hide yes)
			(effects
				(font
					(size 1.016 1.016)
					(thickness 0.1524)
				)
				(justify mirror)
			)
		)
		(duplicate_pad_numbers_are_jumpers no)
		(fp_rect
			(start 0.4318 0.9525)
			(end -0.4318 -0.9525)
			(stroke
				(width 0)
				(type default)
			)
			(fill no)
			(layer "B.CrtYd")
		)
		(fp_rect
			(start 0.4318 0.9525)
			(end -0.4318 -0.9525)
			(stroke
				(width 0)
				(type default)
			)
			(fill no)
			(layer "B.Fab")
		)
		(pad "1" smd custom
			(at 0 -0.4445)
			(size 0.1524 0.1524)
			(layers "B.Cu" "B.Mask" "B.Paste")
			(net "GND")
			(options
				(clearance outline)
				(anchor circle)
			)
			(primitives
				(gr_poly
					(pts
						(arc
							(start 0.3048 0.2032)
							(mid 0.275042 0.275042)
							(end 0.2032 0.3048)
						)
						(arc
							(start -0.2032 0.3048)
							(mid -0.275042 0.275042)
							(end -0.3048 0.2032)
						)
						(arc
							(start -0.3048 -0.2032)
							(mid -0.275042 -0.275042)
							(end -0.2032 -0.3048)
						)
						(arc
							(start 0.2032 -0.3048)
							(mid 0.275042 -0.275042)
							(end 0.3048 -0.2032)
						)
					)
					(width 0)
					(fill yes)
				)
			)
		)
		(pad "2" smd custom
			(at 0 0.4445)
			(size 0.1524 0.1524)
			(layers "B.Cu" "B.Mask" "B.Paste")
			(net "P3V3_STBY")
			(options
				(clearance outline)
				(anchor circle)
			)
			(primitives
				(gr_poly
					(pts
						(arc
							(start 0.3048 0.2032)
							(mid 0.275042 0.275042)
							(end 0.2032 0.3048)
						)
						(arc
							(start -0.2032 0.3048)
							(mid -0.275042 0.275042)
							(end -0.3048 0.2032)
						)
						(arc
							(start -0.3048 -0.2032)
							(mid -0.275042 -0.275042)
							(end -0.2032 -0.3048)
						)
						(arc
							(start 0.2032 -0.3048)
							(mid 0.275042 -0.275042)
							(end 0.3048 -0.2032)
						)
					)
					(width 0)
					(fill yes)
				)
			)
		)
	)
	(footprint ""
		(layer "B.Cu")
		(at 131.294124 -208.889092 180)
		(property "Reference" "R4122"
			(at 0 0 0)
			(layer "B.SilkS")
			(hide yes)
			(effects
				(font
					(size 1.27 1.27)
				)
				(justify mirror)
			)
		)
		(property "Value" "4K7R2F-GP"
			(at -0.064008 -3.993896 180)
			(unlocked yes)
			(layer "B.Fab")
			(hide yes)
			(effects
				(font
					(size 1.016 1.016)
					(thickness 0.1524)
				)
				(justify mirror)
			)
		)
		(property "Device Type" "R402H16"
			(at -0.064008 -5.517896 180)
			(unlocked yes)
			(layer "B.Fab")
			(hide yes)
			(effects
				(font
					(size 1.016 1.016)
					(thickness 0.1524)
				)
				(justify mirror)
			)
		)
		(duplicate_pad_numbers_are_jumpers no)
		(fp_line
			(start 0.508 -0.9398)
			(end 0.508 0.9398)
			(stroke
				(width 0.1524)
				(type default)
			)
			(layer "B.SilkS")
		)
		(fp_line
			(start -0.508 -0.9398)
			(end 0.508 -0.9398)
			(stroke
				(width 0.1524)
				(type default)
			)
			(layer "B.SilkS")
		)
		(fp_rect
			(start 0.508 0.9398)
			(end -0.508 -0.9398)
			(stroke
				(width 0)
				(type default)
			)
			(fill no)
			(layer "B.CrtYd")
		)
		(fp_rect
			(start 0.508 0.9398)
			(end -0.508 -0.9398)
			(stroke
				(width 0)
				(type default)
			)
			(fill no)
			(layer "B.Fab")
		)
		(pad "1" smd custom
			(at 0 -0.4445)
			(size 0.1397 0.1397)
			(layers "B.Cu" "B.Mask" "B.Paste")
			(net "SSD_PERST#6")
			(options
				(clearance outline)
				(anchor circle)
			)
			(primitives
				(gr_poly
					(pts
						(arc
							(start -0.1778 0.2794)
							(mid -0.249642 0.249642)
							(end -0.2794 0.1778)
						)
						(arc
							(start -0.2794 -0.1778)
							(mid -0.249642 -0.249642)
							(end -0.1778 -0.2794)
						)
						(arc
							(start 0.1778 -0.2794)
							(mid 0.249642 -0.249642)
							(end 0.2794 -0.1778)
						)
						(arc
							(start 0.2794 0.1778)
							(mid 0.249642 0.249642)
							(end 0.1778 0.2794)
						)
					)
					(width 0)
					(fill yes)
				)
			)
		)
		(pad "2" smd custom
			(at 0 0.4445)
			(size 0.1397 0.1397)
			(layers "B.Cu" "B.Mask" "B.Paste")
			(net "P3V3_STBY")
			(options
				(clearance outline)
				(anchor circle)
			)
			(primitives
				(gr_poly
					(pts
						(arc
							(start -0.1778 0.2794)
							(mid -0.249642 0.249642)
							(end -0.2794 0.1778)
						)
						(arc
							(start -0.2794 -0.1778)
							(mid -0.249642 -0.249642)
							(end -0.1778 -0.2794)
						)
						(arc
							(start 0.1778 -0.2794)
							(mid 0.249642 -0.249642)
							(end 0.2794 -0.1778)
						)
						(arc
							(start 0.2794 0.1778)
							(mid 0.249642 0.249642)
							(end 0.1778 0.2794)
						)
					)
					(width 0)
					(fill yes)
				)
			)
		)
	)
	(footprint ""
		(layer "B.Cu")
		(at 330.740512 -172.432218 180)
		(property "Reference" "R577"
			(at 0 0 0)
			(layer "B.SilkS")
			(hide yes)
			(effects
				(font
					(size 1.27 1.27)
				)
				(justify mirror)
			)
		)
		(property "Value" "10KR2F-2-GP"
			(at -0.064008 -3.993896 180)
			(unlocked yes)
			(layer "B.Fab")
			(hide yes)
			(effects
				(font
					(size 1.016 1.016)
					(thickness 0.1524)
				)
				(justify mirror)
			)
		)
		(property "Device Type" "R402H16"
			(at -0.064008 -5.517896 180)
			(unlocked yes)
			(layer "B.Fab")
			(hide yes)
			(effects
				(font
					(size 1.016 1.016)
					(thickness 0.1524)
				)
				(justify mirror)
			)
		)
		(duplicate_pad_numbers_are_jumpers no)
		(fp_line
			(start 0.508 -0.9398)
			(end 0.508 0.9398)
			(stroke
				(width 0.1524)
				(type default)
			)
			(layer "B.SilkS")
		)
		(fp_line
			(start -0.508 -0.9398)
			(end 0.508 -0.9398)
			(stroke
				(width 0.1524)
				(type default)
			)
			(layer "B.SilkS")
		)
		(fp_rect
			(start 0.508 0.9398)
			(end -0.508 -0.9398)
			(stroke
				(width 0)
				(type default)
			)
			(fill no)
			(layer "B.CrtYd")
		)
		(fp_rect
			(start 0.508 0.9398)
			(end -0.508 -0.9398)
			(stroke
				(width 0)
				(type default)
			)
			(fill no)
			(layer "B.Fab")
		)
		(pad "1" smd custom
			(at 0 -0.4445)
			(size 0.1397 0.1397)
			(layers "B.Cu" "B.Mask" "B.Paste")
			(net "P3V3_STBY")
			(options
				(clearance outline)
				(anchor circle)
			)
			(primitives
				(gr_poly
					(pts
						(arc
							(start -0.1778 0.2794)
							(mid -0.249642 0.249642)
							(end -0.2794 0.1778)
						)
						(arc
							(start -0.2794 -0.1778)
							(mid -0.249642 -0.249642)
							(end -0.1778 -0.2794)
						)
						(arc
							(start 0.1778 -0.2794)
							(mid 0.249642 -0.249642)
							(end 0.2794 -0.1778)
						)
						(arc
							(start 0.2794 0.1778)
							(mid 0.249642 0.249642)
							(end 0.1778 0.2794)
						)
					)
					(width 0)
					(fill yes)
				)
			)
		)
		(pad "2" smd custom
			(at 0 0.4445)
			(size 0.1397 0.1397)
			(layers "B.Cu" "B.Mask" "B.Paste")
			(net "IOEXP4_AD1")
			(options
				(clearance outline)
				(anchor circle)
			)
			(primitives
				(gr_poly
					(pts
						(arc
							(start -0.1778 0.2794)
							(mid -0.249642 0.249642)
							(end -0.2794 0.1778)
						)
						(arc
							(start -0.2794 -0.1778)
							(mid -0.249642 -0.249642)
							(end -0.1778 -0.2794)
						)
						(arc
							(start 0.1778 -0.2794)
							(mid 0.249642 -0.249642)
							(end 0.2794 -0.1778)
						)
						(arc
							(start 0.2794 0.1778)
							(mid 0.249642 0.249642)
							(end 0.1778 0.2794)
						)
					)
					(width 0)
					(fill yes)
				)
			)
		)
	)
)
